# TIMECARD (Time Appliance Project (Time Card)) — schematic netlist excerpt (pin names and nets, part order shuffled) for the footprints in the layout excerpt that follows; sources: Cadence DE-HDL packaged netlist, KiCad conversion of R4006-B0001-02_R01.brd

R352  RESISTOR  100OHM 1%  pkg SMC_0402R_H016  page 24 : \1\ = R_FT4232_CHC_RX ; \2\ = UART_FT4232_RX_FPGA_TX
C175  CAPACITOR  100UF 6.3V 20%  pkg SMC_1210R_H110  page 14 : \1\ = XP1R0V_FPGA_VCCINT ; \2\ = SG

(kicad_pcb
	(version 20260206)
	(generator "pcbnew")
	(generator_version "10.0")
	(general
		(thickness 1.6)
		(legacy_teardrops no)
	)
	(paper "A4")
	(title_block
		(title "timecard-production-celestica-r4006 — R4006-B0001-02_R01.brd")
		(comment 1 "Time Appliance Project (Time Card) / footprints 51-52 of 1113")
	)
	(layers
		(0 "F.Cu" signal "TOP")
		(4 "In1.Cu" signal "L02_GND1")
		(6 "In2.Cu" signal "L03_SIG1")
		(8 "In3.Cu" signal "L04_GND2")
		(10 "In4.Cu" signal "L05_VCC1")
		(12 "In5.Cu" signal "L06_VCC2")
		(14 "In6.Cu" signal "L07_GND3")
		(16 "In7.Cu" signal "L08_SIG2")
		(18 "In8.Cu" signal "L09_GND4")
		(2 "B.Cu" signal "BOTTOM")
		(9 "F.Adhes" user "F.Adhesive")
		(11 "B.Adhes" user "B.Adhesive")
		(13 "F.Paste" user "Package Geometry/Pastemask Top")
		(15 "B.Paste" user "Package Geometry/Pastemask Bottom")
		(5 "F.SilkS" user "Ref Des/Silkscreen Top")
		(7 "B.SilkS" user "Ref Des/Silkscreen Bottom")
		(1 "F.Mask" user "Board Geometry/Soldermask Top")
		(3 "B.Mask" user "Board Geometry/Soldermask Bottom")
		(17 "Dwgs.User" user "User.Drawings")
		(19 "Cmts.User" user "User.Comments")
		(21 "Eco1.User" user "User.Eco1")
		(23 "Eco2.User" user "User.Eco2")
		(25 "Edge.Cuts" user "Board Geometry/Outline")
		(27 "Margin" user)
		(31 "F.CrtYd" user "Package Geometry/Place Bound Top")
		(29 "B.CrtYd" user "Package Geometry/Place Bound Bottom")
		(35 "F.Fab" user "Ref Des/Assembly Top")
		(33 "B.Fab" user "Ref Des/Assembly Bottom")
	)
	(footprint ""
		(layer "F.Cu")
		(at 28.575 -75.184 -90)
		(property "Reference" "R352"
			(at -0.381 -2.45237 90)
			(unlocked yes)
			(layer "F.SilkS")
			(effects
				(font
					(size 0.7874 0.5842)
					(thickness 0.1524)
				)
			)
		)
		(property "Value" "VAL*"
			(at 0.02032 2.13233 270)
			(unlocked yes)
			(layer "F.Fab")
			(hide yes)
			(effects
				(font
					(size 0.7874 0.5842)
					(thickness 0.1524)
				)
			)
		)
		(property "Tolerance" "TOL*"
			(at 0.044704 3.05435 270)
			(unlocked yes)
			(layer "Cmts.User")
			(hide yes)
			(effects
				(font
					(size 0.7874 0.5842)
					(thickness 0.1524)
				)
			)
		)
		(property "User Part Number" "PARTNUM*"
			(at 0.02032 4.024884 270)
			(unlocked yes)
			(layer "Cmts.User")
			(hide yes)
			(effects
				(font
					(size 0.7874 0.5842)
					(thickness 0.1524)
				)
			)
		)
		(property "Device Type" "RESISTOR-G155-11000-01,100OHM,A"
			(at 0.008382 1.210564 270)
			(unlocked yes)
			(layer "F.Fab")
			(hide yes)
			(effects
				(font
					(size 0.7874 0.5842)
					(thickness 0.1524)
				)
			)
		)
		(duplicate_pad_numbers_are_jumpers no)
		(fp_line
			(start -1.143 0.5588)
			(end 1.143 0.5588)
			(stroke
				(width 0.1)
				(type default)
			)
			(layer "F.SilkS")
		)
		(fp_line
			(start 1.143 0.5588)
			(end 1.143 -0.5588)
			(stroke
				(width 0.1)
				(type default)
			)
			(layer "F.SilkS")
		)
		(fp_line
			(start -1.143 -0.5588)
			(end -1.143 0.5588)
			(stroke
				(width 0.1)
				(type default)
			)
			(layer "F.SilkS")
		)
		(fp_line
			(start 1.143 -0.5588)
			(end -1.143 -0.5588)
			(stroke
				(width 0.1)
				(type default)
			)
			(layer "F.SilkS")
		)
		(fp_poly
			(pts
				(xy -1.143 0.5588) (xy 1.143 0.5588) (xy 1.143 -0.5588) (xy -1.143 -0.5588)
			)
			(stroke
				(width 0)
				(type default)
			)
			(fill no)
			(layer "F.CrtYd")
		)
		(fp_line
			(start -0.508 0.3048)
			(end 0.508 0.3048)
			(stroke
				(width 0.1)
				(type default)
			)
			(layer "F.Fab")
		)
		(fp_line
			(start 0.508 0.3048)
			(end 0.508 -0.3048)
			(stroke
				(width 0.1)
				(type default)
			)
			(layer "F.Fab")
		)
		(fp_line
			(start -0.508 -0.3048)
			(end -0.508 0.3048)
			(stroke
				(width 0.1)
				(type default)
			)
			(layer "F.Fab")
		)
		(fp_line
			(start 0.508 -0.3048)
			(end -0.508 -0.3048)
			(stroke
				(width 0.1)
				(type default)
			)
			(layer "F.Fab")
		)
		(pad "1" smd rect
			(at -0.5334 0 270)
			(size 0.7112 0.6096)
			(layers "F.Cu" "F.Mask" "F.Paste")
			(net "R_FT4232_CHC_RX")
		)
		(pad "2" smd rect
			(at 0.5334 0 270)
			(size 0.7112 0.6096)
			(layers "F.Cu" "F.Mask" "F.Paste")
			(net "UART_FT4232_RX_FPGA_TX")
		)
		(zone
			(layer "F.Cu")
			(hatch none 0.5)
			(connect_pads
				(clearance 0)
			)
			(min_thickness 0.25)
			(keepout
				(tracks not_allowed)
				(vias allowed)
				(pads allowed)
				(copperpour not_allowed)
				(footprints allowed)
			)
			(placement
				(enabled no)
				(sheetname "")
			)
			(fill
				(thermal_gap 0.5)
				(thermal_bridge_width 0.5)
				(island_removal_mode 0)
			)
			(polygon
				(pts
					(xy 28.2702 -75.2602) (xy 28.2702 -75.1078) (xy 28.8798 -75.1078) (xy 28.8798 -75.2602)
				)
			)
		)
		(zone
			(layer "F.Cu")
			(hatch none 0.5)
			(connect_pads
				(clearance 0)
			)
			(min_thickness 0.25)
			(keepout
				(tracks allowed)
				(vias not_allowed)
				(pads allowed)
				(copperpour not_allowed)
				(footprints allowed)
			)
			(placement
				(enabled no)
				(sheetname "")
			)
			(fill
				(thermal_gap 0.5)
				(thermal_bridge_width 0.5)
				(island_removal_mode 0)
			)
			(polygon
				(pts
					(xy 28.2702 -75.2602) (xy 28.2702 -75.1078) (xy 28.8798 -75.1078) (xy 28.8798 -75.2602)
				)
			)
		)
	)
	(footprint ""
		(layer "F.Cu")
		(at 133.223 -40.513)
		(property "Reference" "C175"
			(at 4.445 6.13537 0)
			(unlocked yes)
			(layer "F.SilkS")
			(effects
				(font
					(size 0.7874 0.5842)
					(thickness 0.1524)
				)
			)
		)
		(property "Value" "VAL*"
			(at 0.1016 3.769106 0)
			(unlocked yes)
			(layer "F.Fab")
			(hide yes)
			(effects
				(font
					(size 0.7874 0.5842)
					(thickness 0.1524)
				)
			)
		)
		(property "Tolerance" "TOL*"
			(at 0.127 4.734306 0)
			(unlocked yes)
			(layer "Cmts.User")
			(hide yes)
			(effects
				(font
					(size 0.7874 0.5842)
					(thickness 0.1524)
				)
			)
		)
		(property "User Part Number" "PARTNUM*"
			(at 0.2032 5.801106 0)
			(unlocked yes)
			(layer "Cmts.User")
			(hide yes)
			(effects
				(font
					(size 0.7874 0.5842)
					(thickness 0.1524)
				)
			)
		)
		(property "Device Type" "CAPACITOR-G109-0G107-BM,100UF,A"
			(at 0.0762 2.829306 0)
			(unlocked yes)
			(layer "F.Fab")
			(hide yes)
			(effects
				(font
					(size 0.7874 0.5842)
					(thickness 0.1524)
				)
			)
		)
		(duplicate_pad_numbers_are_jumpers no)
		(fp_line
			(start -2.159 -1.5748)
			(end 2.159 -1.5748)
			(stroke
				(width 0.1)
				(type default)
			)
			(layer "F.SilkS")
		)
		(fp_line
			(start -2.159 1.5748)
			(end -2.159 -1.5748)
			(stroke
				(width 0.1)
				(type default)
			)
			(layer "F.SilkS")
		)
		(fp_line
			(start 2.159 -1.5748)
			(end 2.159 1.5748)
			(stroke
				(width 0.1)
				(type default)
			)
			(layer "F.SilkS")
		)
		(fp_line
			(start 2.159 1.5748)
			(end -2.159 1.5748)
			(stroke
				(width 0.1)
				(type default)
			)
			(layer "F.SilkS")
		)
		(fp_rect
			(start -2.159 -1.5748)
			(end 2.159 1.5748)
			(stroke
				(width 0)
				(type default)
			)
			(fill no)
			(layer "F.CrtYd")
		)
		(fp_line
			(start -1.6002 -1.2446)
			(end -1.6002 1.2446)
			(stroke
				(width 0.1)
				(type default)
			)
			(layer "F.Fab")
		)
		(fp_line
			(start -1.6002 1.2446)
			(end 1.6002 1.2446)
			(stroke
				(width 0.1)
				(type default)
			)
			(layer "F.Fab")
		)
		(fp_line
			(start 1.6002 -1.2446)
			(end -1.6002 -1.2446)
			(stroke
				(width 0.1)
				(type default)
			)
			(layer "F.Fab")
		)
		(fp_line
			(start 1.6002 1.2446)
			(end 1.6002 -1.2446)
			(stroke
				(width 0.1)
				(type default)
			)
			(layer "F.Fab")
		)
		(pad "1" smd rect
			(at -1.3335 0)
			(size 1.143 2.6416)
			(layers "F.Cu" "F.Mask" "F.Paste")
			(net "XP1R0V_FPGA_VCCINT")
		)
		(pad "2" smd rect
			(at 1.3335 0)
			(size 1.143 2.6416)
			(layers "F.Cu" "F.Mask" "F.Paste")
			(net "SG")
		)
		(zone
			(layer "F.Cu")
			(hatch none 0.5)
			(connect_pads
				(clearance 0)
			)
			(min_thickness 0.25)
			(keepout
				(tracks allowed)
				(vias not_allowed)
				(pads allowed)
				(copperpour not_allowed)
				(footprints allowed)
			)
			(placement
				(enabled no)
				(sheetname "")
			)
			(fill
				(thermal_gap 0.5)
				(thermal_bridge_width 0.5)
				(island_removal_mode 0)
			)
			(polygon
				(pts
					(xy 132.5372 -41.91) (xy 132.5372 -39.116) (xy 133.9088 -39.116) (xy 133.9088 -41.91)
				)
			)
		)
	)
)
